(kicad_pcb
	(version 20260206)
	(generator "pcbnew")
	(generator_version "10.0")
	(general
		(thickness 1.6)
		(legacy_teardrops no)
	)
	(paper "A4")
	(title_block
		(title "panther-plus-userver — 13130-1b_20150205.brd")
		(comment 1 "Honey Badger (Wiwynn) / footprints 1424-1432 of 1509")
	)
	(layers
		(0 "F.Cu" signal "TOP")
		(4 "In1.Cu" signal "L2")
		(6 "In2.Cu" signal "L3")
		(8 "In3.Cu" signal "L4")
		(10 "In4.Cu" signal "L5")
		(12 "In5.Cu" signal "L6")
		(14 "In6.Cu" signal "L7")
		(16 "In7.Cu" signal "L8")
		(18 "In8.Cu" signal "L9")
		(20 "In9.Cu" signal "L10")
		(22 "In10.Cu" signal "L11")
		(2 "B.Cu" signal "BOTTOM")
		(9 "F.Adhes" user "F.Adhesive")
		(11 "B.Adhes" user "B.Adhesive")
		(13 "F.Paste" user "Package Geometry/Pastemask Top")
		(15 "B.Paste" user "Package Geometry/Pastemask Bottom")
		(5 "F.SilkS" user "Ref Des/Silkscreen Top")
		(7 "B.SilkS" user "Ref Des/Silkscreen Bottom")
		(1 "F.Mask" user "Board Geometry/Soldermask Top")
		(3 "B.Mask" user "Board Geometry/Soldermask Bottom")
		(17 "Dwgs.User" user "User.Drawings")
		(19 "Cmts.User" user "User.Comments")
		(21 "Eco1.User" user "User.Eco1")
		(23 "Eco2.User" user "User.Eco2")
		(25 "Edge.Cuts" user "Board Geometry/Outline")
		(27 "Margin" user)
		(31 "F.CrtYd" user "Package Geometry/Place Bound Top")
		(29 "B.CrtYd" user "Package Geometry/Place Bound Bottom")
		(35 "F.Fab" user "Ref Des/Assembly Top")
		(33 "B.Fab" user "Ref Des/Assembly Bottom")
	)
	(footprint ""
		(layer "B.Cu")
		(at 78.613 -36.6268 -90)
		(property "Reference" "C200"
			(at 0 0 90)
			(layer "B.SilkS")
			(hide yes)
			(effects
				(font
					(size 1.27 1.27)
				)
				(justify mirror)
			)
		)
		(property "Value" "SCD1U16V2KX-3GP"
			(at -1.1811 -2.7051 270)
			(unlocked yes)
			(layer "B.Fab")
			(hide yes)
			(effects
				(font
					(size 1.016 1.016)
					(thickness 0.1524)
				)
				(justify mirror)
			)
		)
		(property "Device Type" "C402H22"
			(at -1.1811 -4.2291 270)
			(unlocked yes)
			(layer "B.Fab")
			(hide yes)
			(effects
				(font
					(size 1.016 1.016)
					(thickness 0.1524)
				)
				(justify mirror)
			)
		)
		(duplicate_pad_numbers_are_jumpers no)
		(fp_rect
			(start 0.381 0.7366)
			(end -0.381 -0.7366)
			(stroke
				(width 0)
				(type default)
			)
			(fill no)
			(layer "B.CrtYd")
		)
		(fp_rect
			(start 0.381 0.7366)
			(end -0.381 -0.7366)
			(stroke
				(width 0)
				(type default)
			)
			(fill no)
			(layer "B.Fab")
		)
		(pad "1" smd custom
			(at 0 -0.4572 90)
			(size 0.1143 0.1143)
			(layers "B.Cu" "B.Mask" "B.Paste")
			(net "RTC_EXTPAD")
			(options
				(clearance outline)
				(anchor circle)
			)
			(primitives
				(gr_poly
					(pts
						(arc
							(start -0.254 0.1778)
							(mid -0.239121 0.213721)
							(end -0.2032 0.2286)
						)
						(arc
							(start 0.2032 0.2286)
							(mid 0.239121 0.213721)
							(end 0.254 0.1778)
						)
						(arc
							(start 0.254 -0.1778)
							(mid 0.239121 -0.213721)
							(end 0.2032 -0.2286)
						)
						(arc
							(start -0.2032 -0.2286)
							(mid -0.239121 -0.213721)
							(end -0.254 -0.1778)
						)
					)
					(width 0)
					(fill yes)
				)
			)
		)
		(pad "2" smd custom
			(at 0 0.4572 90)
			(size 0.1143 0.1143)
			(layers "B.Cu" "B.Mask" "B.Paste")
			(net "GND")
			(options
				(clearance outline)
				(anchor circle)
			)
			(primitives
				(gr_poly
					(pts
						(arc
							(start -0.254 0.1778)
							(mid -0.239121 0.213721)
							(end -0.2032 0.2286)
						)
						(arc
							(start 0.2032 0.2286)
							(mid 0.239121 0.213721)
							(end 0.254 0.1778)
						)
						(arc
							(start 0.254 -0.1778)
							(mid 0.239121 -0.213721)
							(end 0.2032 -0.2286)
						)
						(arc
							(start -0.2032 -0.2286)
							(mid -0.239121 -0.213721)
							(end -0.254 -0.1778)
						)
					)
					(width 0)
					(fill yes)
				)
			)
		)
	)
	(footprint ""
		(layer "B.Cu")
		(at 193.548 -40.386)
		(property "Reference" "PD2"
			(at 0 0 0)
			(layer "B.SilkS")
			(hide yes)
			(effects
				(font
					(size 1.27 1.27)
				)
				(justify mirror)
			)
		)
		(property "Value" "MM3Z5V6T1G-GP"
			(at -2.5527 -1.9812 0)
			(unlocked yes)
			(layer "B.Fab")
			(hide yes)
			(effects
				(font
					(size 1.016 1.016)
					(thickness 0.1524)
				)
				(justify mirror)
			)
		)
		(property "Device Type" "SOD323AKH40"
			(at -2.5527 -3.5052 0)
			(unlocked yes)
			(layer "B.Fab")
			(hide yes)
			(effects
				(font
					(size 1.016 1.016)
					(thickness 0.1524)
				)
				(justify mirror)
			)
		)
		(duplicate_pad_numbers_are_jumpers no)
		(fp_line
			(start -0.7747 1.7653)
			(end 0.7747 1.7653)
			(stroke
				(width 0.254)
				(type default)
			)
			(layer "B.SilkS")
		)
		(fp_rect
			(start 0.9017 1.6383)
			(end -0.9017 -1.6383)
			(stroke
				(width 0)
				(type default)
			)
			(fill no)
			(layer "B.CrtYd")
		)
		(fp_rect
			(start 0.9017 1.6383)
			(end -0.9017 -1.6383)
			(stroke
				(width 0)
				(type default)
			)
			(fill no)
			(layer "B.Fab")
		)
		(pad "A" smd rect
			(at 0 -1.100074 180)
			(size 0.5588 0.8128)
			(layers "B.Cu" "B.Mask" "B.Paste")
			(net "GND")
		)
		(pad "K" smd rect
			(at 0 1.100074 180)
			(size 0.5588 0.8128)
			(layers "B.Cu" "B.Mask" "B.Paste")
			(net "VDDR_Z")
		)
	)
	(footprint ""
		(layer "B.Cu")
		(at 53.848 -12.7 180)
		(property "Reference" "R393"
			(at 0 0 0)
			(layer "B.SilkS")
			(hide yes)
			(effects
				(font
					(size 1.27 1.27)
				)
				(justify mirror)
			)
		)
		(property "Value" "0R2J-2-GP"
			(at -1.7907 -1.1176 180)
			(unlocked yes)
			(layer "B.Fab")
			(hide yes)
			(effects
				(font
					(size 1.016 1.016)
					(thickness 0.1524)
				)
				(justify mirror)
			)
		)
		(property "Device Type" "R402H16"
			(at -1.7907 -2.6416 180)
			(unlocked yes)
			(layer "B.Fab")
			(hide yes)
			(effects
				(font
					(size 1.016 1.016)
					(thickness 0.1524)
				)
				(justify mirror)
			)
		)
		(duplicate_pad_numbers_are_jumpers no)
		(fp_rect
			(start 0.381 0.8382)
			(end -0.381 -0.8382)
			(stroke
				(width 0)
				(type default)
			)
			(fill no)
			(layer "B.CrtYd")
		)
		(fp_rect
			(start 0.381 0.8382)
			(end -0.381 -0.8382)
			(stroke
				(width 0)
				(type default)
			)
			(fill no)
			(layer "B.Fab")
		)
		(pad "1" smd custom
			(at 0 -0.4318)
			(size 0.127 0.127)
			(layers "B.Cu" "B.Mask" "B.Paste")
			(net "GBE_R_SMBCLK")
			(options
				(clearance outline)
				(anchor circle)
			)
			(primitives
				(gr_poly
					(pts
						(arc
							(start -0.2032 0.2794)
							(mid -0.239121 0.264521)
							(end -0.254 0.2286)
						)
						(arc
							(start -0.254 -0.2286)
							(mid -0.239121 -0.264521)
							(end -0.2032 -0.2794)
						)
						(arc
							(start 0.2032 -0.2794)
							(mid 0.239121 -0.264521)
							(end 0.254 -0.2286)
						)
						(arc
							(start 0.254 0.2286)
							(mid 0.239121 0.264521)
							(end 0.2032 0.2794)
						)
					)
					(width 0)
					(fill yes)
				)
			)
		)
		(pad "2" smd custom
			(at 0 0.4318)
			(size 0.127 0.127)
			(layers "B.Cu" "B.Mask" "B.Paste")
			(net "GF_GBE_SMBCLK")
			(options
				(clearance outline)
				(anchor circle)
			)
			(primitives
				(gr_poly
					(pts
						(arc
							(start -0.2032 0.2794)
							(mid -0.239121 0.264521)
							(end -0.254 0.2286)
						)
						(arc
							(start -0.254 -0.2286)
							(mid -0.239121 -0.264521)
							(end -0.2032 -0.2794)
						)
						(arc
							(start 0.2032 -0.2794)
							(mid 0.239121 -0.264521)
							(end 0.254 -0.2286)
						)
						(arc
							(start 0.254 0.2286)
							(mid 0.239121 0.264521)
							(end 0.2032 0.2794)
						)
					)
					(width 0)
					(fill yes)
				)
			)
		)
	)
	(footprint ""
		(layer "B.Cu")
		(at 67.0814 -38.8874 180)
		(property "Reference" "PR127"
			(at 0 0 0)
			(layer "B.SilkS")
			(hide yes)
			(effects
				(font
					(size 1.27 1.27)
				)
				(justify mirror)
			)
		)
		(property "Value" "0R2J-2-GP"
			(at -1.7907 -1.1176 180)
			(unlocked yes)
			(layer "B.Fab")
			(hide yes)
			(effects
				(font
					(size 1.016 1.016)
					(thickness 0.1524)
				)
				(justify mirror)
			)
		)
		(property "Device Type" "R402H16"
			(at -1.7907 -2.6416 180)
			(unlocked yes)
			(layer "B.Fab")
			(hide yes)
			(effects
				(font
					(size 1.016 1.016)
					(thickness 0.1524)
				)
				(justify mirror)
			)
		)
		(duplicate_pad_numbers_are_jumpers no)
		(fp_rect
			(start 0.381 0.8382)
			(end -0.381 -0.8382)
			(stroke
				(width 0)
				(type default)
			)
			(fill no)
			(layer "B.CrtYd")
		)
		(fp_rect
			(start 0.381 0.8382)
			(end -0.381 -0.8382)
			(stroke
				(width 0)
				(type default)
			)
			(fill no)
			(layer "B.Fab")
		)
		(pad "1" smd custom
			(at 0 -0.4318)
			(size 0.127 0.127)
			(layers "B.Cu" "B.Mask" "B.Paste")
			(net "PMU_SLP_DDRVTT#")
			(options
				(clearance outline)
				(anchor circle)
			)
			(primitives
				(gr_poly
					(pts
						(arc
							(start -0.2032 0.2794)
							(mid -0.239121 0.264521)
							(end -0.254 0.2286)
						)
						(arc
							(start -0.254 -0.2286)
							(mid -0.239121 -0.264521)
							(end -0.2032 -0.2794)
						)
						(arc
							(start 0.2032 -0.2794)
							(mid 0.239121 -0.264521)
							(end 0.254 -0.2286)
						)
						(arc
							(start 0.254 0.2286)
							(mid 0.239121 0.264521)
							(end 0.2032 0.2794)
						)
					)
					(width 0)
					(fill yes)
				)
			)
		)
		(pad "2" smd custom
			(at 0 0.4318)
			(size 0.127 0.127)
			(layers "B.Cu" "B.Mask" "B.Paste")
			(net "PVTT_DDR_EN")
			(options
				(clearance outline)
				(anchor circle)
			)
			(primitives
				(gr_poly
					(pts
						(arc
							(start -0.2032 0.2794)
							(mid -0.239121 0.264521)
							(end -0.254 0.2286)
						)
						(arc
							(start -0.254 -0.2286)
							(mid -0.239121 -0.264521)
							(end -0.2032 -0.2794)
						)
						(arc
							(start 0.2032 -0.2794)
							(mid 0.239121 -0.264521)
							(end 0.254 -0.2286)
						)
						(arc
							(start 0.254 0.2286)
							(mid 0.239121 0.264521)
							(end 0.2032 0.2794)
						)
					)
					(width 0)
					(fill yes)
				)
			)
		)
	)
	(footprint ""
		(layer "B.Cu")
		(at 5.5372 -28.321 -90)
		(property "Reference" "PC81"
			(at 0 0 90)
			(layer "B.SilkS")
			(hide yes)
			(effects
				(font
					(size 1.27 1.27)
				)
				(justify mirror)
			)
		)
		(property "Value" "SC22U25V5MX-GP"
			(at 0 -4.9022 270)
			(unlocked yes)
			(layer "B.Fab")
			(hide yes)
			(effects
				(font
					(size 1.016 1.016)
					(thickness 0.1524)
				)
				(justify mirror)
			)
		)
		(property "Device Type" "C805H58"
			(at 0 -6.8072 270)
			(unlocked yes)
			(layer "B.Fab")
			(hide yes)
			(effects
				(font
					(size 1.016 1.016)
					(thickness 0.1524)
				)
				(justify mirror)
			)
		)
		(duplicate_pad_numbers_are_jumpers no)
		(fp_line
			(start -0.6096 0)
			(end 0.6096 0)
			(stroke
				(width 0.3048)
				(type default)
			)
			(layer "B.SilkS")
		)
		(fp_poly
			(pts
				(xy 0.9017 1.4351) (xy -0.9017 1.4351) (xy -0.9017 -1.4351) (xy 0.9017 -1.4351)
			)
			(stroke
				(width 0)
				(type default)
			)
			(fill no)
			(layer "B.CrtYd")
		)
		(fp_poly
			(pts
				(xy -0.9017 1.4351) (xy -0.9017 -1.4351) (xy 0.9017 -1.4351) (xy 0.9017 1.4351)
			)
			(stroke
				(width 0)
				(type default)
			)
			(fill no)
			(layer "B.Fab")
		)
		(pad "1" smd rect
			(at 0 -0.8382 90)
			(size 1.5494 0.9398)
			(layers "B.Cu" "B.Mask" "B.Paste")
			(net "P1V0_VIN")
		)
		(pad "2" smd rect
			(at 0 0.8382 90)
			(size 1.5494 0.9398)
			(layers "B.Cu" "B.Mask" "B.Paste")
			(net "GND")
		)
	)
	(footprint ""
		(layer "B.Cu")
		(at 38.23081 -12.7)
		(property "Reference" "C266"
			(at 0 0 0)
			(layer "B.SilkS")
			(hide yes)
			(effects
				(font
					(size 1.27 1.27)
				)
				(justify mirror)
			)
		)
		(property "Value" "SCD1U16V2KX-3GP"
			(at -1.1811 -2.7051 0)
			(unlocked yes)
			(layer "B.Fab")
			(hide yes)
			(effects
				(font
					(size 1.016 1.016)
					(thickness 0.1524)
				)
				(justify mirror)
			)
		)
		(property "Device Type" "C402H22"
			(at -1.1811 -4.2291 0)
			(unlocked yes)
			(layer "B.Fab")
			(hide yes)
			(effects
				(font
					(size 1.016 1.016)
					(thickness 0.1524)
				)
				(justify mirror)
			)
		)
		(duplicate_pad_numbers_are_jumpers no)
		(fp_rect
			(start 0.381 0.7366)
			(end -0.381 -0.7366)
			(stroke
				(width 0)
				(type default)
			)
			(fill no)
			(layer "B.CrtYd")
		)
		(fp_rect
			(start 0.381 0.7366)
			(end -0.381 -0.7366)
			(stroke
				(width 0)
				(type default)
			)
			(fill no)
			(layer "B.Fab")
		)
		(pad "1" smd custom
			(at 0 -0.4572 180)
			(size 0.1143 0.1143)
			(layers "B.Cu" "B.Mask" "B.Paste")
			(net "P2E_CPU_SAS_C_TX_DP6")
			(options
				(clearance outline)
				(anchor circle)
			)
			(primitives
				(gr_poly
					(pts
						(arc
							(start -0.254 0.1778)
							(mid -0.239121 0.213721)
							(end -0.2032 0.2286)
						)
						(arc
							(start 0.2032 0.2286)
							(mid 0.239121 0.213721)
							(end 0.254 0.1778)
						)
						(arc
							(start 0.254 -0.1778)
							(mid 0.239121 -0.213721)
							(end 0.2032 -0.2286)
						)
						(arc
							(start -0.2032 -0.2286)
							(mid -0.239121 -0.213721)
							(end -0.254 -0.1778)
						)
					)
					(width 0)
					(fill yes)
				)
			)
		)
		(pad "2" smd custom
			(at 0 0.4572 180)
			(size 0.1143 0.1143)
			(layers "B.Cu" "B.Mask" "B.Paste")
			(net "P2E_CPU_SAS_TX_DP6")
			(options
				(clearance outline)
				(anchor circle)
			)
			(primitives
				(gr_poly
					(pts
						(arc
							(start -0.254 0.1778)
							(mid -0.239121 0.213721)
							(end -0.2032 0.2286)
						)
						(arc
							(start 0.2032 0.2286)
							(mid 0.239121 0.213721)
							(end 0.254 0.1778)
						)
						(arc
							(start 0.254 -0.1778)
							(mid 0.239121 -0.213721)
							(end 0.2032 -0.2286)
						)
						(arc
							(start -0.2032 -0.2286)
							(mid -0.239121 -0.213721)
							(end -0.254 -0.1778)
						)
					)
					(width 0)
					(fill yes)
				)
			)
		)
	)
	(footprint ""
		(layer "B.Cu")
		(at 163.068 -59.309)
		(property "Reference" "C362"
			(at 0 0 0)
			(layer "B.SilkS")
			(hide yes)
			(effects
				(font
					(size 1.27 1.27)
				)
				(justify mirror)
			)
		)
		(property "Value" "SC47U6D3V5MX-1-GP"
			(at 0 -4.9022 0)
			(unlocked yes)
			(layer "B.Fab")
			(hide yes)
			(effects
				(font
					(size 1.016 1.016)
					(thickness 0.1524)
				)
				(justify mirror)
			)
		)
		(property "Device Type" "C805H54"
			(at 0 -6.8072 0)
			(unlocked yes)
			(layer "B.Fab")
			(hide yes)
			(effects
				(font
					(size 1.016 1.016)
					(thickness 0.1524)
				)
				(justify mirror)
			)
		)
		(duplicate_pad_numbers_are_jumpers no)
		(fp_line
			(start -0.6096 0)
			(end 0.6096 0)
			(stroke
				(width 0.3048)
				(type default)
			)
			(layer "B.SilkS")
		)
		(fp_poly
			(pts
				(xy 0.9017 1.4351) (xy -0.9017 1.4351) (xy -0.9017 -1.4351) (xy 0.9017 -1.4351)
			)
			(stroke
				(width 0)
				(type default)
			)
			(fill no)
			(layer "B.CrtYd")
		)
		(fp_poly
			(pts
				(xy -0.9017 1.4351) (xy -0.9017 -1.4351) (xy 0.9017 -1.4351) (xy 0.9017 1.4351)
			)
			(stroke
				(width 0)
				(type default)
			)
			(fill no)
			(layer "B.Fab")
		)
		(pad "1" smd rect
			(at 0 -0.8382 180)
			(size 1.5494 0.9398)
			(layers "B.Cu" "B.Mask" "B.Paste")
			(net "PV_VDDR")
		)
		(pad "2" smd rect
			(at 0 0.8382 180)
			(size 1.5494 0.9398)
			(layers "B.Cu" "B.Mask" "B.Paste")
			(net "GND")
		)
	)
	(footprint ""
		(layer "B.Cu")
		(at 17.526 -57.9882)
		(property "Reference" "PR12"
			(at 0 0 0)
			(layer "B.SilkS")
			(hide yes)
			(effects
				(font
					(size 1.27 1.27)
				)
				(justify mirror)
			)
		)
		(property "Value" "100R3F-1-GP"
			(at 0.0254 -2.0193 0)
			(unlocked yes)
			(layer "B.Fab")
			(hide yes)
			(effects
				(font
					(size 1.016 1.016)
					(thickness 0.1524)
				)
				(justify mirror)
			)
		)
		(property "Device Type" "R603H22"
			(at 0.0254 -3.5433 0)
			(unlocked yes)
			(layer "B.Fab")
			(hide yes)
			(effects
				(font
					(size 1.016 1.016)
					(thickness 0.1524)
				)
				(justify mirror)
			)
		)
		(duplicate_pad_numbers_are_jumpers no)
		(fp_line
			(start -0.4318 0)
			(end -0.2032 0)
			(stroke
				(width 0.2032)
				(type default)
			)
			(layer "B.SilkS")
		)
		(fp_line
			(start 0.2032 0)
			(end 0.4191 0)
			(stroke
				(width 0.2032)
				(type default)
			)
			(layer "B.SilkS")
		)
		(fp_rect
			(start 0.635 1.1811)
			(end -0.635 -1.1811)
			(stroke
				(width 0)
				(type default)
			)
			(fill no)
			(layer "B.CrtYd")
		)
		(fp_rect
			(start 0.635 1.1811)
			(end -0.635 -1.1811)
			(stroke
				(width 0)
				(type default)
			)
			(fill no)
			(layer "B.Fab")
		)
		(pad "1" smd custom
			(at 0 -0.6604 180)
			(size 0.19685 0.19685)
			(layers "B.Cu" "B.Mask" "B.Paste")
			(net "VR_PVNN_FB")
			(options
				(clearance outline)
				(anchor circle)
			)
			(primitives
				(gr_poly
					(pts
						(arc
							(start 0.508 0.2921)
							(mid 0.478242 0.363942)
							(end 0.4064 0.3937)
						)
						(arc
							(start -0.4064 0.3937)
							(mid -0.478242 0.363942)
							(end -0.508 0.2921)
						)
						(arc
							(start -0.508 -0.2921)
							(mid -0.478242 -0.363942)
							(end -0.4064 -0.3937)
						)
						(arc
							(start 0.4064 -0.3937)
							(mid 0.478242 -0.363942)
							(end 0.508 -0.2921)
						)
					)
					(width 0)
					(fill yes)
				)
			)
		)
		(pad "2" smd custom
			(at 0 0.6604 180)
			(size 0.19685 0.19685)
			(layers "B.Cu" "B.Mask" "B.Paste")
			(net "VR_PVNN_VSEN_R")
			(options
				(clearance outline)
				(anchor circle)
			)
			(primitives
				(gr_poly
					(pts
						(arc
							(start 0.508 0.2921)
							(mid 0.478242 0.363942)
							(end 0.4064 0.3937)
						)
						(arc
							(start -0.4064 0.3937)
							(mid -0.478242 0.363942)
							(end -0.508 0.2921)
						)
						(arc
							(start -0.508 -0.2921)
							(mid -0.478242 -0.363942)
							(end -0.4064 -0.3937)
						)
						(arc
							(start 0.4064 -0.3937)
							(mid 0.478242 -0.363942)
							(end 0.508 -0.2921)
						)
					)
					(width 0)
					(fill yes)
				)
			)
		)
	)
	(footprint ""
		(layer "B.Cu")
		(at 26.797 -49.149)
		(property "Reference" "PC128"
			(at 0 0 0)
			(layer "B.SilkS")
			(hide yes)
			(effects
				(font
					(size 1.27 1.27)
				)
				(justify mirror)
			)
		)
		(property "Value" "SCD1U16V2KX-3GP"
			(at -1.8923 -1.2065 0)
			(unlocked yes)
			(layer "B.Fab")
			(hide yes)
			(effects
				(font
					(size 1.016 1.016)
					(thickness 0.1524)
				)
				(justify mirror)
			)
		)
		(property "Device Type" "C402H22"
			(at -1.8923 -2.7305 0)
			(unlocked yes)
			(layer "B.Fab")
			(hide yes)
			(effects
				(font
					(size 1.016 1.016)
					(thickness 0.1524)
				)
				(justify mirror)
			)
		)
		(duplicate_pad_numbers_are_jumpers no)
		(fp_rect
			(start 0.381 0.7366)
			(end -0.381 -0.7366)
			(stroke
				(width 0)
				(type default)
			)
			(fill no)
			(layer "B.CrtYd")
		)
		(fp_rect
			(start 0.381 0.7366)
			(end -0.381 -0.7366)
			(stroke
				(width 0)
				(type default)
			)
			(fill no)
			(layer "B.Fab")
		)
		(pad "1" smd custom
			(at 0 -0.4572 180)
			(size 0.1143 0.1143)
			(layers "B.Cu" "B.Mask" "B.Paste")
			(net "P1V5_STBY_IN")
			(options
				(clearance outline)
				(anchor circle)
			)
			(primitives
				(gr_poly
					(pts
						(arc
							(start -0.254 0.1778)
							(mid -0.239121 0.213721)
							(end -0.2032 0.2286)
						)
						(arc
							(start 0.2032 0.2286)
							(mid 0.239121 0.213721)
							(end 0.254 0.1778)
						)
						(arc
							(start 0.254 -0.1778)
							(mid 0.239121 -0.213721)
							(end 0.2032 -0.2286)
						)
						(arc
							(start -0.2032 -0.2286)
							(mid -0.239121 -0.213721)
							(end -0.254 -0.1778)
						)
					)
					(width 0)
					(fill yes)
				)
			)
		)
		(pad "2" smd custom
			(at 0 0.4572 180)
			(size 0.1143 0.1143)
			(layers "B.Cu" "B.Mask" "B.Paste")
			(net "GND")
			(options
				(clearance outline)
				(anchor circle)
			)
			(primitives
				(gr_poly
					(pts
						(arc
							(start -0.254 0.1778)
							(mid -0.239121 0.213721)
							(end -0.2032 0.2286)
						)
						(arc
							(start 0.2032 0.2286)
							(mid 0.239121 0.213721)
							(end 0.254 0.1778)
						)
						(arc
							(start 0.254 -0.1778)
							(mid 0.239121 -0.213721)
							(end 0.2032 -0.2286)
						)
						(arc
							(start -0.2032 -0.2286)
							(mid -0.239121 -0.213721)
							(end -0.254 -0.1778)
						)
					)
					(width 0)
					(fill yes)
				)
			)
		)
	)
)
